# TIMECARD (Time Appliance Project (Time Card)) — schematic netlist excerpt (pin names and nets, part order shuffled) for the footprints in the layout excerpt that follows; sources: Cadence DE-HDL packaged netlist, KiCad conversion of R4006-B0001-02_R01.brd

C269  CAPACITOR  47UF 4V 20%  pkg SMC_0805R_H057  page 29 : \1\ = XP1R0V_FPGA ; \2\ = SG
L5  INDUCTOR_2  1.0UH 20%  pkg SMC_L_287X260_V1_H197  page 29 : \1\ = XP1R0V_SW ; \2\ = XP1R0V_FPGA

(kicad_pcb
	(version 20260206)
	(generator "pcbnew")
	(generator_version "10.0")
	(general
		(thickness 1.6)
		(legacy_teardrops no)
	)
	(paper "A4")
	(title_block
		(title "timecard-production-celestica-r4006 — R4006-B0001-02_R01.brd")
		(comment 1 "Time Appliance Project (Time Card) / footprints 323-324 of 1113")
	)
	(layers
		(0 "F.Cu" signal "TOP")
		(4 "In1.Cu" signal "L02_GND1")
		(6 "In2.Cu" signal "L03_SIG1")
		(8 "In3.Cu" signal "L04_GND2")
		(10 "In4.Cu" signal "L05_VCC1")
		(12 "In5.Cu" signal "L06_VCC2")
		(14 "In6.Cu" signal "L07_GND3")
		(16 "In7.Cu" signal "L08_SIG2")
		(18 "In8.Cu" signal "L09_GND4")
		(2 "B.Cu" signal "BOTTOM")
		(9 "F.Adhes" user "F.Adhesive")
		(11 "B.Adhes" user "B.Adhesive")
		(13 "F.Paste" user "Package Geometry/Pastemask Top")
		(15 "B.Paste" user "Package Geometry/Pastemask Bottom")
		(5 "F.SilkS" user "Ref Des/Silkscreen Top")
		(7 "B.SilkS" user "Ref Des/Silkscreen Bottom")
		(1 "F.Mask" user "Board Geometry/Soldermask Top")
		(3 "B.Mask" user "Board Geometry/Soldermask Bottom")
		(17 "Dwgs.User" user "User.Drawings")
		(19 "Cmts.User" user "User.Comments")
		(21 "Eco1.User" user "User.Eco1")
		(23 "Eco2.User" user "User.Eco2")
		(25 "Edge.Cuts" user "Board Geometry/Outline")
		(27 "Margin" user)
		(31 "F.CrtYd" user "Package Geometry/Place Bound Top")
		(29 "B.CrtYd" user "Package Geometry/Place Bound Bottom")
		(35 "F.Fab" user "Ref Des/Assembly Top")
		(33 "B.Fab" user "Ref Des/Assembly Bottom")
	)
	(footprint ""
		(layer "F.Cu")
		(at 144.526 -40.894)
		(property "Reference" "C269"
			(at 0.127 1.56337 0)
			(unlocked yes)
			(layer "F.SilkS")
			(effects
				(font
					(size 0.7874 0.5842)
					(thickness 0.1524)
				)
			)
		)
		(property "Value" "VAL*"
			(at 0.0762 3.134106 0)
			(unlocked yes)
			(layer "F.Fab")
			(hide yes)
			(effects
				(font
					(size 0.7874 0.5842)
					(thickness 0.1524)
				)
			)
		)
		(property "Tolerance" "TOL*"
			(at 0.0762 4.048506 0)
			(unlocked yes)
			(layer "Cmts.User")
			(hide yes)
			(effects
				(font
					(size 0.7874 0.5842)
					(thickness 0.1524)
				)
			)
		)
		(property "User Part Number" "PARTNUM*"
			(at 0.1016 5.013706 0)
			(unlocked yes)
			(layer "Cmts.User")
			(hide yes)
			(effects
				(font
					(size 0.7874 0.5842)
					(thickness 0.1524)
				)
			)
		)
		(property "Device Type" "CAPACITOR-G107-0F476-AM,47UF,2A"
			(at 0.0508 2.194306 0)
			(unlocked yes)
			(layer "F.Fab")
			(hide yes)
			(effects
				(font
					(size 0.7874 0.5842)
					(thickness 0.1524)
				)
			)
		)
		(duplicate_pad_numbers_are_jumpers no)
		(fp_line
			(start -1.5748 -0.9398)
			(end -1.5748 0.9398)
			(stroke
				(width 0.1)
				(type default)
			)
			(layer "F.SilkS")
		)
		(fp_line
			(start -1.5748 0.9398)
			(end 1.5748 0.9398)
			(stroke
				(width 0.1)
				(type default)
			)
			(layer "F.SilkS")
		)
		(fp_line
			(start 1.5748 -0.9398)
			(end -1.5748 -0.9398)
			(stroke
				(width 0.1)
				(type default)
			)
			(layer "F.SilkS")
		)
		(fp_line
			(start 1.5748 0.9398)
			(end 1.5748 -0.9398)
			(stroke
				(width 0.1)
				(type default)
			)
			(layer "F.SilkS")
		)
		(fp_rect
			(start -1.5748 0.9398)
			(end 1.5748 -0.9398)
			(stroke
				(width 0)
				(type default)
			)
			(fill no)
			(layer "F.CrtYd")
		)
		(fp_line
			(start -1.016 -0.635)
			(end -1.016 0.635)
			(stroke
				(width 0.1)
				(type default)
			)
			(layer "F.Fab")
		)
		(fp_line
			(start -1.016 0.635)
			(end 1.016 0.635)
			(stroke
				(width 0.1)
				(type default)
			)
			(layer "F.Fab")
		)
		(fp_line
			(start 1.016 -0.635)
			(end -1.016 -0.635)
			(stroke
				(width 0.1)
				(type default)
			)
			(layer "F.Fab")
		)
		(fp_line
			(start 1.016 0.635)
			(end 1.016 -0.635)
			(stroke
				(width 0.1)
				(type default)
			)
			(layer "F.Fab")
		)
		(pad "1" smd rect
			(at -0.8382 0)
			(size 0.9652 1.3716)
			(layers "F.Cu" "F.Mask" "F.Paste")
			(net "XP1R0V_FPGA")
		)
		(pad "2" smd rect
			(at 0.8382 0)
			(size 0.9652 1.3716)
			(layers "F.Cu" "F.Mask" "F.Paste")
			(net "SG")
		)
		(zone
			(layer "F.Cu")
			(hatch none 0.5)
			(connect_pads
				(clearance 0)
			)
			(min_thickness 0.25)
			(keepout
				(tracks not_allowed)
				(vias allowed)
				(pads allowed)
				(copperpour not_allowed)
				(footprints allowed)
			)
			(placement
				(enabled no)
				(sheetname "")
			)
			(fill
				(thermal_gap 0.5)
				(thermal_bridge_width 0.5)
				(island_removal_mode 0)
			)
			(polygon
				(pts
					(xy 144.2974 -40.259) (xy 144.7546 -40.259) (xy 144.7546 -41.529) (xy 144.2974 -41.529)
				)
			)
		)
		(zone
			(layer "F.Cu")
			(hatch none 0.5)
			(connect_pads
				(clearance 0)
			)
			(min_thickness 0.25)
			(keepout
				(tracks allowed)
				(vias not_allowed)
				(pads allowed)
				(copperpour not_allowed)
				(footprints allowed)
			)
			(placement
				(enabled no)
				(sheetname "")
			)
			(fill
				(thermal_gap 0.5)
				(thermal_bridge_width 0.5)
				(island_removal_mode 0)
			)
			(polygon
				(pts
					(xy 144.2974 -40.259) (xy 144.7546 -40.259) (xy 144.7546 -41.529) (xy 144.2974 -41.529)
				)
			)
		)
	)
	(footprint ""
		(layer "F.Cu")
		(at 142.1638 -46.6852 -90)
		(property "Reference" "L5"
			(at 5.32257 3.7846 0)
			(unlocked yes)
			(layer "F.SilkS")
			(effects
				(font
					(size 0.7874 0.5842)
					(thickness 0.1524)
				)
				(justify left)
			)
		)
		(property "Value" "VALUE*"
			(at -3.56489 13.891006 270)
			(unlocked yes)
			(layer "F.Fab")
			(hide yes)
			(effects
				(font
					(size 1.6002 1.1938)
					(thickness 0.000001)
				)
				(justify left)
			)
		)
		(property "Device Type" "INDUCTOR_2-G190-10418-01,1.0UHA"
			(at -2.219706 11.425936 270)
			(unlocked yes)
			(layer "F.Fab")
			(hide yes)
			(effects
				(font
					(size 1.6002 1.1938)
					(thickness 0.000001)
				)
				(justify left)
			)
		)
		(property "User Part Number" "PARTNUM*"
			(at -5.249926 16.101314 270)
			(unlocked yes)
			(layer "Cmts.User")
			(hide yes)
			(effects
				(font
					(size 1.6002 1.1938)
					(thickness 0.000001)
				)
				(justify left)
			)
		)
		(property "Tolerance" "TOL*"
			(at -2.304542 9.300718 270)
			(unlocked yes)
			(layer "Cmts.User")
			(hide yes)
			(effects
				(font
					(size 1.6002 1.1938)
					(thickness 0.000001)
				)
				(justify left)
			)
		)
		(duplicate_pad_numbers_are_jumpers no)
		(fp_line
			(start -4.452366 3.704082)
			(end -4.452366 -3.704082)
			(stroke
				(width 0.1)
				(type default)
			)
			(layer "F.SilkS")
		)
		(fp_line
			(start 4.452112 3.704082)
			(end -4.452366 3.704082)
			(stroke
				(width 0.1)
				(type default)
			)
			(layer "F.SilkS")
		)
		(fp_line
			(start -4.452366 -3.704082)
			(end 4.452112 -3.704082)
			(stroke
				(width 0.1)
				(type default)
			)
			(layer "F.SilkS")
		)
		(fp_line
			(start 4.452112 -3.704082)
			(end 4.452112 3.704082)
			(stroke
				(width 0.1)
				(type default)
			)
			(layer "F.SilkS")
		)
		(fp_rect
			(start -4.706366 3.958082)
			(end 4.706112 -3.958082)
			(stroke
				(width 0)
				(type default)
			)
			(fill no)
			(layer "F.CrtYd")
		)
		(fp_line
			(start -3.79984 3.450082)
			(end 3.79984 3.450082)
			(stroke
				(width 0.1)
				(type default)
			)
			(layer "F.Fab")
		)
		(fp_line
			(start 3.79984 3.450082)
			(end 3.79984 -3.450082)
			(stroke
				(width 0.1)
				(type default)
			)
			(layer "F.Fab")
		)
		(fp_line
			(start -3.79984 -3.450082)
			(end -3.79984 3.450082)
			(stroke
				(width 0.1)
				(type default)
			)
			(layer "F.Fab")
		)
		(fp_line
			(start 3.79984 -3.450082)
			(end -3.79984 -3.450082)
			(stroke
				(width 0.1)
				(type default)
			)
			(layer "F.Fab")
		)
		(fp_text user "1"
			(at -3.44805 -4.0132 0)
			(unlocked yes)
			(layer "F.SilkS")
			(effects
				(font
					(size 0.635 0.4064)
					(thickness 0.1524)
				)
			)
		)
		(fp_text user "2"
			(at 3.79857 -4.5212 0)
			(unlocked yes)
			(layer "F.SilkS")
			(effects
				(font
					(size 0.7874 0.5842)
					(thickness 0.1524)
				)
			)
		)
		(fp_text user "1"
			(at -5.19049 0.16891 90)
			(unlocked yes)
			(layer "F.Fab")
			(effects
				(font
					(size 0.7874 0.5842)
					(thickness 0.1524)
				)
			)
		)
		(fp_text user "2"
			(at 5.190236 0.084074 90)
			(unlocked yes)
			(layer "F.Fab")
			(effects
				(font
					(size 0.7874 0.5842)
					(thickness 0.1524)
				)
			)
		)
		(pad "1" smd rect
			(at -2.725166 0 270)
			(size 2.9464 3.5052)
			(layers "F.Cu" "F.Mask" "F.Paste")
			(net "XP1R0V_SW")
		)
		(pad "2" smd rect
			(at 2.724912 0 270)
			(size 2.9464 3.5052)
			(layers "F.Cu" "F.Mask" "F.Paste")
			(net "XP1R0V_FPGA")
		)
	)
)
